# S9S_MB_2U (Grand Teton) — schematic netlist excerpt (pin names and nets, part order shuffled) for the footprints in the layout excerpt that follows; sources: Cadence DE-HDL packaged netlist, KiCad conversion of 03242023_DA0F0TMBIJ0_F0T_Motherboard_J_brd_V01_OCP.brd

R2786  Q_RES  0 5% CHIP  pkg 0402LF  page 152 : A = USB2_HUB_SWB_DP ; B = USB2_HUB_BUF_SWB_R_DP
PR1778  Q_RES  3.3 1% CHIP  pkg 0402LF  page 276 : A = SW_PVCCFA_EHV_CPU0_BOOT1 ; B = SW_PVCCFA_EHV_CPU0_BOOT1_R

(kicad_pcb
	(version 20260206)
	(generator "pcbnew")
	(generator_version "10.0")
	(general
		(thickness 1.6)
		(legacy_teardrops no)
	)
	(paper "A4")
	(title_block
		(title "03242023_DA0F0TMBIJ0_F0T_Motherboard_J_brd_V01_OCP.brd")
		(comment 1 "Grand Teton / footprints 2526-2527 of 6105")
	)
	(layers
		(0 "F.Cu" signal "TOP")
		(4 "In1.Cu" signal "GND")
		(6 "In2.Cu" signal "IN1")
		(8 "In3.Cu" signal "GND1")
		(10 "In4.Cu" signal "IN2")
		(12 "In5.Cu" signal "GND2")
		(14 "In6.Cu" signal "IN3")
		(16 "In7.Cu" signal "GND3")
		(18 "In8.Cu" signal "VCC")
		(20 "In9.Cu" signal "VCC1")
		(22 "In10.Cu" signal "GND4")
		(24 "In11.Cu" signal "IN4")
		(26 "In12.Cu" signal "GND5")
		(28 "In13.Cu" signal "IN5")
		(30 "In14.Cu" signal "GND6")
		(32 "In15.Cu" signal "IN6")
		(34 "In16.Cu" signal "GND7")
		(2 "B.Cu" signal "BOTTOM")
		(9 "F.Adhes" user "F.Adhesive")
		(11 "B.Adhes" user "B.Adhesive")
		(13 "F.Paste" user "Package Geometry/Pastemask Top")
		(15 "B.Paste" user "Package Geometry/Pastemask Bottom")
		(5 "F.SilkS" user "Ref Des/Silkscreen Top")
		(7 "B.SilkS" user "Ref Des/Silkscreen Bottom")
		(1 "F.Mask" user "Board Geometry/Soldermask Top")
		(3 "B.Mask" user "Board Geometry/Soldermask Bottom")
		(17 "Dwgs.User" user "User.Drawings")
		(19 "Cmts.User" user "User.Comments")
		(21 "Eco1.User" user "User.Eco1")
		(23 "Eco2.User" user "User.Eco2")
		(25 "Edge.Cuts" user "Board Geometry/Outline")
		(27 "Margin" user)
		(31 "F.CrtYd" user "Package Geometry/Place Bound Top")
		(29 "B.CrtYd" user "Package Geometry/Place Bound Bottom")
		(35 "F.Fab" user "Ref Des/Assembly Top")
		(33 "B.Fab" user "Ref Des/Assembly Bottom")
	)
	(footprint ""
		(layer "F.Cu")
		(at 422.74744 -152.024588)
		(property "Reference" "PR1778"
			(at 0 0 0)
			(layer "F.SilkS")
			(hide yes)
			(effects
				(font
					(size 1.27 1.27)
				)
			)
		)
		(property "Value" ""
			(at 0 0 0)
			(layer "F.Fab")
			(effects
				(font
					(size 1.27 1.27)
				)
			)
		)
		(duplicate_pad_numbers_are_jumpers no)
		(fp_line
			(start -0.7874 -0.4064)
			(end 0.7874 -0.4064)
			(stroke
				(width 0.1524)
				(type default)
			)
			(layer "F.SilkS")
		)
		(fp_line
			(start -0.7874 0.4064)
			(end -0.7874 -0.4064)
			(stroke
				(width 0.1524)
				(type default)
			)
			(layer "F.SilkS")
		)
		(fp_line
			(start 0.7874 -0.4064)
			(end 0.7874 0.4064)
			(stroke
				(width 0.1524)
				(type default)
			)
			(layer "F.SilkS")
		)
		(fp_line
			(start 0.7874 0.4064)
			(end -0.7874 0.4064)
			(stroke
				(width 0.1524)
				(type default)
			)
			(layer "F.SilkS")
		)
		(fp_line
			(start -0.67945 -0.305054)
			(end -0.12065 -0.305054)
			(stroke
				(width 0.1)
				(type default)
			)
			(layer "F.Fab")
		)
		(fp_line
			(start -0.67945 0.3048)
			(end -0.67945 -0.305054)
			(stroke
				(width 0.1)
				(type default)
			)
			(layer "F.Fab")
		)
		(fp_line
			(start -0.12065 -0.305054)
			(end -0.12065 -0.2794)
			(stroke
				(width 0.1)
				(type default)
			)
			(layer "F.Fab")
		)
		(fp_line
			(start -0.12065 -0.2794)
			(end 0.12065 -0.2794)
			(stroke
				(width 0.1)
				(type default)
			)
			(layer "F.Fab")
		)
		(fp_line
			(start -0.12065 0.2794)
			(end -0.12065 0.3048)
			(stroke
				(width 0.1)
				(type default)
			)
			(layer "F.Fab")
		)
		(fp_line
			(start -0.12065 0.3048)
			(end -0.67945 0.3048)
			(stroke
				(width 0.1)
				(type default)
			)
			(layer "F.Fab")
		)
		(fp_line
			(start 0.120396 0.2794)
			(end -0.12065 0.2794)
			(stroke
				(width 0.1)
				(type default)
			)
			(layer "F.Fab")
		)
		(fp_line
			(start 0.120396 0.3048)
			(end 0.120396 0.2794)
			(stroke
				(width 0.1)
				(type default)
			)
			(layer "F.Fab")
		)
		(fp_line
			(start 0.12065 -0.3048)
			(end 0.67945 -0.3048)
			(stroke
				(width 0.1)
				(type default)
			)
			(layer "F.Fab")
		)
		(fp_line
			(start 0.12065 -0.2794)
			(end 0.12065 -0.3048)
			(stroke
				(width 0.1)
				(type default)
			)
			(layer "F.Fab")
		)
		(fp_line
			(start 0.67945 -0.3048)
			(end 0.67945 0.3048)
			(stroke
				(width 0.1)
				(type default)
			)
			(layer "F.Fab")
		)
		(fp_line
			(start 0.67945 0.3048)
			(end 0.120396 0.3048)
			(stroke
				(width 0.1)
				(type default)
			)
			(layer "F.Fab")
		)
		(pad "1" smd circle
			(at -0.40005 0)
			(size 0 0)
			(layers "F.Cu" "F.Mask" "F.Paste")
			(net "SW_PVCCFA_EHV_CPU0_BOOT1")
		)
		(pad "2" smd circle
			(at 0.40005 0)
			(size 0 0)
			(layers "F.Cu" "F.Mask" "F.Paste")
			(net "SW_PVCCFA_EHV_CPU0_BOOT1_R")
		)
	)
	(footprint ""
		(layer "F.Cu")
		(at 11.421618 -105.48239 90)
		(property "Reference" "R2786"
			(at 0 0 90)
			(layer "F.SilkS")
			(hide yes)
			(effects
				(font
					(size 1.27 1.27)
				)
			)
		)
		(property "Value" ""
			(at 0 0 90)
			(layer "F.Fab")
			(effects
				(font
					(size 1.27 1.27)
				)
			)
		)
		(duplicate_pad_numbers_are_jumpers no)
		(fp_line
			(start 0.7874 -0.4064)
			(end 0.7874 0.4064)
			(stroke
				(width 0.1524)
				(type default)
			)
			(layer "F.SilkS")
		)
		(fp_line
			(start -0.7874 -0.4064)
			(end 0.7874 -0.4064)
			(stroke
				(width 0.1524)
				(type default)
			)
			(layer "F.SilkS")
		)
		(fp_line
			(start 0.01651 0.4064)
			(end -0.7874 0.4064)
			(stroke
				(width 0.1524)
				(type default)
			)
			(layer "F.SilkS")
		)
		(fp_line
			(start -0.12065 -0.305054)
			(end -0.12065 -0.2794)
			(stroke
				(width 0.1)
				(type default)
			)
			(layer "F.Fab")
		)
		(fp_line
			(start -0.67945 -0.305054)
			(end -0.12065 -0.305054)
			(stroke
				(width 0.1)
				(type default)
			)
			(layer "F.Fab")
		)
		(fp_line
			(start 0.67945 -0.3048)
			(end 0.67945 0.3048)
			(stroke
				(width 0.1)
				(type default)
			)
			(layer "F.Fab")
		)
		(fp_line
			(start 0.12065 -0.3048)
			(end 0.67945 -0.3048)
			(stroke
				(width 0.1)
				(type default)
			)
			(layer "F.Fab")
		)
		(fp_line
			(start 0.12065 -0.2794)
			(end 0.12065 -0.3048)
			(stroke
				(width 0.1)
				(type default)
			)
			(layer "F.Fab")
		)
		(fp_line
			(start -0.12065 -0.2794)
			(end 0.12065 -0.2794)
			(stroke
				(width 0.1)
				(type default)
			)
			(layer "F.Fab")
		)
		(fp_line
			(start 0.120396 0.2794)
			(end -0.12065 0.2794)
			(stroke
				(width 0.1)
				(type default)
			)
			(layer "F.Fab")
		)
		(fp_line
			(start -0.12065 0.2794)
			(end -0.12065 0.3048)
			(stroke
				(width 0.1)
				(type default)
			)
			(layer "F.Fab")
		)
		(fp_line
			(start 0.67945 0.3048)
			(end 0.120396 0.3048)
			(stroke
				(width 0.1)
				(type default)
			)
			(layer "F.Fab")
		)
		(fp_line
			(start 0.120396 0.3048)
			(end 0.120396 0.2794)
			(stroke
				(width 0.1)
				(type default)
			)
			(layer "F.Fab")
		)
		(fp_line
			(start -0.12065 0.3048)
			(end -0.67945 0.3048)
			(stroke
				(width 0.1)
				(type default)
			)
			(layer "F.Fab")
		)
		(fp_line
			(start -0.67945 0.3048)
			(end -0.67945 -0.305054)
			(stroke
				(width 0.1)
				(type default)
			)
			(layer "F.Fab")
		)
		(pad "1" smd rect
			(at -0.40005 0 270)
			(size 0.4572 0.508)
			(layers "F.Cu" "F.Mask" "F.Paste")
			(net "USB2_HUB_SWB_DP")
		)
		(pad "2" smd rect
			(at 0.40005 0 270)
			(size 0.4572 0.508)
			(layers "F.Cu" "F.Mask" "F.Paste")
			(net "USB2_HUB_BUF_SWB_R_DP")
		)
	)
)
